(kicad_pcb
	(version 20260206)
	(generator "pcbnew")
	(generator_version "10.0")
	(general
		(thickness 1.6)
		(legacy_teardrops no)
	)
	(paper "A4")
	(title_block
		(title "peb — Lightning_PEB_BRD.brd")
		(comment 1 "Lightning (Wiwynn / Facebook NVMe JBOF) / footprints 1903-1910 of 2563")
	)
	(layers
		(0 "F.Cu" signal "TOP")
		(4 "In1.Cu" signal "L2GND")
		(6 "In2.Cu" signal "L3")
		(8 "In3.Cu" signal "L4VCC")
		(10 "In4.Cu" signal "L5VCC")
		(12 "In5.Cu" signal "L6")
		(14 "In6.Cu" signal "L7GND")
		(2 "B.Cu" signal "BOTTOM")
		(9 "F.Adhes" user "F.Adhesive")
		(11 "B.Adhes" user "B.Adhesive")
		(13 "F.Paste" user "Package Geometry/Pastemask Top")
		(15 "B.Paste" user "Package Geometry/Pastemask Bottom")
		(5 "F.SilkS" user "Ref Des/Silkscreen Top")
		(7 "B.SilkS" user "Ref Des/Silkscreen Bottom")
		(1 "F.Mask" user "Board Geometry/Soldermask Top")
		(3 "B.Mask" user "Board Geometry/Soldermask Bottom")
		(17 "Dwgs.User" user "User.Drawings")
		(19 "Cmts.User" user "User.Comments")
		(21 "Eco1.User" user "User.Eco1")
		(23 "Eco2.User" user "User.Eco2")
		(25 "Edge.Cuts" user "Board Geometry/Outline")
		(27 "Margin" user)
		(31 "F.CrtYd" user "Package Geometry/Place Bound Top")
		(29 "B.CrtYd" user "Package Geometry/Place Bound Bottom")
		(35 "F.Fab" user "Ref Des/Assembly Top")
		(33 "B.Fab" user "Ref Des/Assembly Bottom")
	)
	(footprint ""
		(layer "B.Cu")
		(at 252.6538 -26.1112)
		(property "Reference" "R1"
			(at 0 0 0)
			(layer "B.SilkS")
			(hide yes)
			(effects
				(font
					(size 1.27 1.27)
				)
				(justify mirror)
			)
		)
		(property "Value" "0R2J-2-GP"
			(at -0.064008 -3.993896 0)
			(unlocked yes)
			(layer "B.Fab")
			(hide yes)
			(effects
				(font
					(size 1.016 1.016)
					(thickness 0.1524)
				)
				(justify mirror)
			)
		)
		(property "Device Type" "R402H16"
			(at -0.064008 -5.517896 0)
			(unlocked yes)
			(layer "B.Fab")
			(hide yes)
			(effects
				(font
					(size 1.016 1.016)
					(thickness 0.1524)
				)
				(justify mirror)
			)
		)
		(duplicate_pad_numbers_are_jumpers no)
		(fp_line
			(start -0.508 -0.9398)
			(end 0.508 -0.9398)
			(stroke
				(width 0.1524)
				(type default)
			)
			(layer "B.SilkS")
		)
		(fp_line
			(start 0.508 -0.9398)
			(end 0.508 0.9398)
			(stroke
				(width 0.1524)
				(type default)
			)
			(layer "B.SilkS")
		)
		(fp_rect
			(start 0.508 0.9398)
			(end -0.508 -0.9398)
			(stroke
				(width 0)
				(type default)
			)
			(fill no)
			(layer "B.CrtYd")
		)
		(fp_rect
			(start 0.508 0.9398)
			(end -0.508 -0.9398)
			(stroke
				(width 0)
				(type default)
			)
			(fill no)
			(layer "B.Fab")
		)
		(pad "1" smd custom
			(at 0 -0.4445 180)
			(size 0.1397 0.1397)
			(layers "B.Cu" "B.Mask" "B.Paste")
			(net "AVS_ENB_R")
			(options
				(clearance outline)
				(anchor circle)
			)
			(primitives
				(gr_poly
					(pts
						(arc
							(start -0.1778 0.2794)
							(mid -0.249642 0.249642)
							(end -0.2794 0.1778)
						)
						(arc
							(start -0.2794 -0.1778)
							(mid -0.249642 -0.249642)
							(end -0.1778 -0.2794)
						)
						(arc
							(start 0.1778 -0.2794)
							(mid 0.249642 -0.249642)
							(end 0.2794 -0.1778)
						)
						(arc
							(start 0.2794 0.1778)
							(mid 0.249642 0.249642)
							(end 0.1778 0.2794)
						)
					)
					(width 0)
					(fill yes)
				)
			)
		)
		(pad "2" smd custom
			(at 0 0.4445 180)
			(size 0.1397 0.1397)
			(layers "B.Cu" "B.Mask" "B.Paste")
			(net "AVS_ENB")
			(options
				(clearance outline)
				(anchor circle)
			)
			(primitives
				(gr_poly
					(pts
						(arc
							(start -0.1778 0.2794)
							(mid -0.249642 0.249642)
							(end -0.2794 0.1778)
						)
						(arc
							(start -0.2794 -0.1778)
							(mid -0.249642 -0.249642)
							(end -0.1778 -0.2794)
						)
						(arc
							(start 0.1778 -0.2794)
							(mid 0.249642 -0.249642)
							(end 0.2794 -0.1778)
						)
						(arc
							(start 0.2794 0.1778)
							(mid 0.249642 0.249642)
							(end 0.1778 0.2794)
						)
					)
					(width 0)
					(fill yes)
				)
			)
		)
	)
	(footprint ""
		(layer "B.Cu")
		(at 228.6254 -45.000672 90)
		(property "Reference" "C489"
			(at 0 0 90)
			(layer "B.SilkS")
			(hide yes)
			(effects
				(font
					(size 1.27 1.27)
				)
				(justify mirror)
			)
		)
		(property "Value" "SCD1U16V1KX-1-GP"
			(at 2.8321 -1.7399 90)
			(unlocked yes)
			(layer "B.Fab")
			(hide yes)
			(effects
				(font
					(size 1.016 1.016)
					(thickness 0.1524)
				)
				(justify mirror)
			)
		)
		(property "Device Type" "C0201H13"
			(at 2.8321 -3.2639 90)
			(unlocked yes)
			(layer "B.Fab")
			(hide yes)
			(effects
				(font
					(size 1.016 1.016)
					(thickness 0.1524)
				)
				(justify mirror)
			)
		)
		(duplicate_pad_numbers_are_jumpers no)
		(fp_rect
			(start 0.2794 0.6477)
			(end -0.2794 -0.6477)
			(stroke
				(width 0)
				(type default)
			)
			(fill no)
			(layer "B.CrtYd")
		)
		(fp_rect
			(start 0.2794 0.6477)
			(end -0.2794 -0.6477)
			(stroke
				(width 0)
				(type default)
			)
			(fill no)
			(layer "B.Fab")
		)
		(pad "1" smd custom
			(at 0 -0.2794 270)
			(size 0.0762 0.0762)
			(layers "B.Cu" "B.Mask" "B.Paste")
			(net "DUT_AVD_PCIE")
			(options
				(clearance outline)
				(anchor circle)
			)
			(primitives
				(gr_poly
					(pts
						(arc
							(start 0.1524 0.127)
							(mid 0.137521 0.162921)
							(end 0.1016 0.1778)
						)
						(arc
							(start -0.1016 0.1778)
							(mid -0.137521 0.162921)
							(end -0.1524 0.127)
						)
						(arc
							(start -0.1524 -0.127)
							(mid -0.137521 -0.162921)
							(end -0.1016 -0.1778)
						)
						(arc
							(start 0.1016 -0.1778)
							(mid 0.137521 -0.162921)
							(end 0.1524 -0.127)
						)
					)
					(width 0)
					(fill yes)
				)
			)
		)
		(pad "2" smd custom
			(at 0 0.2794 270)
			(size 0.0762 0.0762)
			(layers "B.Cu" "B.Mask" "B.Paste")
			(net "GND")
			(options
				(clearance outline)
				(anchor circle)
			)
			(primitives
				(gr_poly
					(pts
						(arc
							(start 0.1524 0.127)
							(mid 0.137521 0.162921)
							(end 0.1016 0.1778)
						)
						(arc
							(start -0.1016 0.1778)
							(mid -0.137521 0.162921)
							(end -0.1524 0.127)
						)
						(arc
							(start -0.1524 -0.127)
							(mid -0.137521 -0.162921)
							(end -0.1016 -0.1778)
						)
						(arc
							(start 0.1016 -0.1778)
							(mid 0.137521 -0.162921)
							(end 0.1524 -0.127)
						)
					)
					(width 0)
					(fill yes)
				)
			)
		)
	)
	(footprint ""
		(layer "B.Cu")
		(at 180.9242 -71.628 180)
		(property "Reference" "C618"
			(at 0 0 0)
			(layer "B.SilkS")
			(hide yes)
			(effects
				(font
					(size 1.27 1.27)
				)
				(justify mirror)
			)
		)
		(property "Value" "SC4D7U16V5KX-1-GP"
			(at 0.0762 -6.1214 180)
			(unlocked yes)
			(layer "B.Fab")
			(hide yes)
			(effects
				(font
					(size 1.016 1.016)
					(thickness 0.1524)
				)
				(justify mirror)
			)
		)
		(property "Device Type" "C805H56"
			(at 0.0762 -8.1534 180)
			(unlocked yes)
			(layer "B.Fab")
			(hide yes)
			(effects
				(font
					(size 1.016 1.016)
					(thickness 0.1524)
				)
				(justify mirror)
			)
		)
		(duplicate_pad_numbers_are_jumpers no)
		(fp_line
			(start -0.635 0)
			(end 0.635 0)
			(stroke
				(width 0.508)
				(type default)
			)
			(layer "B.SilkS")
		)
		(fp_rect
			(start 0.9652 1.778)
			(end -0.9652 -1.778)
			(stroke
				(width 0)
				(type default)
			)
			(fill no)
			(layer "B.CrtYd")
		)
		(fp_poly
			(pts
				(xy 0.9652 -1.778) (xy -0.9652 -1.778) (xy -0.9652 1.778) (xy 0.9652 1.778)
			)
			(stroke
				(width 0)
				(type default)
			)
			(fill no)
			(layer "B.Fab")
		)
		(pad "1" smd rect
			(at 0 -0.9652)
			(size 1.397 1.143)
			(layers "B.Cu" "B.Mask" "B.Paste")
			(net "DUT_AVD_PCIE")
		)
		(pad "2" smd rect
			(at 0 0.9652)
			(size 1.397 1.143)
			(layers "B.Cu" "B.Mask" "B.Paste")
			(net "GND")
		)
	)
	(footprint ""
		(layer "B.Cu")
		(at 20.400518 -125.497844 90)
		(property "Reference" "R241"
			(at 0 0 90)
			(layer "B.SilkS")
			(hide yes)
			(effects
				(font
					(size 1.27 1.27)
				)
				(justify mirror)
			)
		)
		(property "Value" "0R2J-2-GP"
			(at -0.064008 -3.993896 90)
			(unlocked yes)
			(layer "B.Fab")
			(hide yes)
			(effects
				(font
					(size 1.016 1.016)
					(thickness 0.1524)
				)
				(justify mirror)
			)
		)
		(property "Device Type" "R402H16"
			(at -0.064008 -5.517896 90)
			(unlocked yes)
			(layer "B.Fab")
			(hide yes)
			(effects
				(font
					(size 1.016 1.016)
					(thickness 0.1524)
				)
				(justify mirror)
			)
		)
		(duplicate_pad_numbers_are_jumpers no)
		(fp_line
			(start 0.508 -0.9398)
			(end 0.508 0.9398)
			(stroke
				(width 0.1524)
				(type default)
			)
			(layer "B.SilkS")
		)
		(fp_line
			(start -0.508 -0.9398)
			(end 0.508 -0.9398)
			(stroke
				(width 0.1524)
				(type default)
			)
			(layer "B.SilkS")
		)
		(fp_rect
			(start 0.508 0.9398)
			(end -0.508 -0.9398)
			(stroke
				(width 0)
				(type default)
			)
			(fill no)
			(layer "B.CrtYd")
		)
		(fp_rect
			(start 0.508 0.9398)
			(end -0.508 -0.9398)
			(stroke
				(width 0)
				(type default)
			)
			(fill no)
			(layer "B.Fab")
		)
		(pad "1" smd custom
			(at 0 -0.4445 270)
			(size 0.1397 0.1397)
			(layers "B.Cu" "B.Mask" "B.Paste")
			(net "BMC_I2C2_MINI2_SDA_S")
			(options
				(clearance outline)
				(anchor circle)
			)
			(primitives
				(gr_poly
					(pts
						(arc
							(start -0.1778 0.2794)
							(mid -0.249642 0.249642)
							(end -0.2794 0.1778)
						)
						(arc
							(start -0.2794 -0.1778)
							(mid -0.249642 -0.249642)
							(end -0.1778 -0.2794)
						)
						(arc
							(start 0.1778 -0.2794)
							(mid 0.249642 -0.249642)
							(end 0.2794 -0.1778)
						)
						(arc
							(start 0.2794 0.1778)
							(mid 0.249642 0.249642)
							(end 0.1778 0.2794)
						)
					)
					(width 0)
					(fill yes)
				)
			)
		)
		(pad "2" smd custom
			(at 0 0.4445 270)
			(size 0.1397 0.1397)
			(layers "B.Cu" "B.Mask" "B.Paste")
			(net "BMC0_SMB2_DAT")
			(options
				(clearance outline)
				(anchor circle)
			)
			(primitives
				(gr_poly
					(pts
						(arc
							(start -0.1778 0.2794)
							(mid -0.249642 0.249642)
							(end -0.2794 0.1778)
						)
						(arc
							(start -0.2794 -0.1778)
							(mid -0.249642 -0.249642)
							(end -0.1778 -0.2794)
						)
						(arc
							(start 0.1778 -0.2794)
							(mid 0.249642 -0.249642)
							(end 0.2794 -0.1778)
						)
						(arc
							(start 0.2794 0.1778)
							(mid 0.249642 0.249642)
							(end 0.1778 0.2794)
						)
					)
					(width 0)
					(fill yes)
				)
			)
		)
	)
	(footprint ""
		(layer "B.Cu")
		(at 225.114104 -203.710032 180)
		(property "Reference" "R4138"
			(at 0 0 0)
			(layer "B.SilkS")
			(hide yes)
			(effects
				(font
					(size 1.27 1.27)
				)
				(justify mirror)
			)
		)
		(property "Value" "4K7R2F-GP"
			(at -0.064008 -3.993896 180)
			(unlocked yes)
			(layer "B.Fab")
			(hide yes)
			(effects
				(font
					(size 1.016 1.016)
					(thickness 0.1524)
				)
				(justify mirror)
			)
		)
		(property "Device Type" "R402H16"
			(at -0.064008 -5.517896 180)
			(unlocked yes)
			(layer "B.Fab")
			(hide yes)
			(effects
				(font
					(size 1.016 1.016)
					(thickness 0.1524)
				)
				(justify mirror)
			)
		)
		(duplicate_pad_numbers_are_jumpers no)
		(fp_line
			(start 0.508 -0.9398)
			(end 0.508 0.9398)
			(stroke
				(width 0.1524)
				(type default)
			)
			(layer "B.SilkS")
		)
		(fp_line
			(start -0.508 -0.9398)
			(end 0.508 -0.9398)
			(stroke
				(width 0.1524)
				(type default)
			)
			(layer "B.SilkS")
		)
		(fp_rect
			(start 0.508 0.9398)
			(end -0.508 -0.9398)
			(stroke
				(width 0)
				(type default)
			)
			(fill no)
			(layer "B.CrtYd")
		)
		(fp_rect
			(start 0.508 0.9398)
			(end -0.508 -0.9398)
			(stroke
				(width 0)
				(type default)
			)
			(fill no)
			(layer "B.Fab")
		)
		(pad "1" smd custom
			(at 0 -0.4445)
			(size 0.1397 0.1397)
			(layers "B.Cu" "B.Mask" "B.Paste")
			(net "SSD_PERST#12")
			(options
				(clearance outline)
				(anchor circle)
			)
			(primitives
				(gr_poly
					(pts
						(arc
							(start -0.1778 0.2794)
							(mid -0.249642 0.249642)
							(end -0.2794 0.1778)
						)
						(arc
							(start -0.2794 -0.1778)
							(mid -0.249642 -0.249642)
							(end -0.1778 -0.2794)
						)
						(arc
							(start 0.1778 -0.2794)
							(mid 0.249642 -0.249642)
							(end 0.2794 -0.1778)
						)
						(arc
							(start 0.2794 0.1778)
							(mid 0.249642 0.249642)
							(end 0.1778 0.2794)
						)
					)
					(width 0)
					(fill yes)
				)
			)
		)
		(pad "2" smd custom
			(at 0 0.4445)
			(size 0.1397 0.1397)
			(layers "B.Cu" "B.Mask" "B.Paste")
			(net "P3V3_STBY")
			(options
				(clearance outline)
				(anchor circle)
			)
			(primitives
				(gr_poly
					(pts
						(arc
							(start -0.1778 0.2794)
							(mid -0.249642 0.249642)
							(end -0.2794 0.1778)
						)
						(arc
							(start -0.2794 -0.1778)
							(mid -0.249642 -0.249642)
							(end -0.1778 -0.2794)
						)
						(arc
							(start 0.1778 -0.2794)
							(mid 0.249642 -0.249642)
							(end 0.2794 -0.1778)
						)
						(arc
							(start 0.2794 0.1778)
							(mid 0.249642 0.249642)
							(end 0.1778 0.2794)
						)
					)
					(width 0)
					(fill yes)
				)
			)
		)
	)
	(footprint ""
		(layer "B.Cu")
		(at 53.721 -135.763 -90)
		(property "Reference" "R322"
			(at 0 0 90)
			(layer "B.SilkS")
			(hide yes)
			(effects
				(font
					(size 1.27 1.27)
				)
				(justify mirror)
			)
		)
		(property "Value" "0R2J-2-GP"
			(at -0.064008 -3.993896 270)
			(unlocked yes)
			(layer "B.Fab")
			(hide yes)
			(effects
				(font
					(size 1.016 1.016)
					(thickness 0.1524)
				)
				(justify mirror)
			)
		)
		(property "Device Type" "R402H16"
			(at -0.064008 -5.517896 270)
			(unlocked yes)
			(layer "B.Fab")
			(hide yes)
			(effects
				(font
					(size 1.016 1.016)
					(thickness 0.1524)
				)
				(justify mirror)
			)
		)
		(duplicate_pad_numbers_are_jumpers no)
		(fp_line
			(start -0.508 -0.9398)
			(end 0.508 -0.9398)
			(stroke
				(width 0.1524)
				(type default)
			)
			(layer "B.SilkS")
		)
		(fp_line
			(start 0.508 -0.9398)
			(end 0.508 0.9398)
			(stroke
				(width 0.1524)
				(type default)
			)
			(layer "B.SilkS")
		)
		(fp_rect
			(start 0.508 0.9398)
			(end -0.508 -0.9398)
			(stroke
				(width 0)
				(type default)
			)
			(fill no)
			(layer "B.CrtYd")
		)
		(fp_rect
			(start 0.508 0.9398)
			(end -0.508 -0.9398)
			(stroke
				(width 0)
				(type default)
			)
			(fill no)
			(layer "B.Fab")
		)
		(pad "1" smd custom
			(at 0 -0.4445 90)
			(size 0.1397 0.1397)
			(layers "B.Cu" "B.Mask" "B.Paste")
			(net "ADC_P0V9_E")
			(options
				(clearance outline)
				(anchor circle)
			)
			(primitives
				(gr_poly
					(pts
						(arc
							(start -0.1778 0.2794)
							(mid -0.249642 0.249642)
							(end -0.2794 0.1778)
						)
						(arc
							(start -0.2794 -0.1778)
							(mid -0.249642 -0.249642)
							(end -0.1778 -0.2794)
						)
						(arc
							(start 0.1778 -0.2794)
							(mid 0.249642 -0.249642)
							(end 0.2794 -0.1778)
						)
						(arc
							(start 0.2794 0.1778)
							(mid 0.249642 0.249642)
							(end 0.1778 0.2794)
						)
					)
					(width 0)
					(fill yes)
				)
			)
		)
		(pad "2" smd custom
			(at 0 0.4445 90)
			(size 0.1397 0.1397)
			(layers "B.Cu" "B.Mask" "B.Paste")
			(net "ADC_P0V9_E_BMC")
			(options
				(clearance outline)
				(anchor circle)
			)
			(primitives
				(gr_poly
					(pts
						(arc
							(start -0.1778 0.2794)
							(mid -0.249642 0.249642)
							(end -0.2794 0.1778)
						)
						(arc
							(start -0.2794 -0.1778)
							(mid -0.249642 -0.249642)
							(end -0.1778 -0.2794)
						)
						(arc
							(start 0.1778 -0.2794)
							(mid 0.249642 -0.249642)
							(end 0.2794 -0.1778)
						)
						(arc
							(start 0.2794 0.1778)
							(mid 0.249642 0.249642)
							(end 0.1778 0.2794)
						)
					)
					(width 0)
					(fill yes)
				)
			)
		)
	)
	(footprint ""
		(layer "B.Cu")
		(at 40.259 -133.223)
		(property "Reference" "C211"
			(at 0 0 0)
			(layer "B.SilkS")
			(hide yes)
			(effects
				(font
					(size 1.27 1.27)
				)
				(justify mirror)
			)
		)
		(property "Value" "SC220P50V2KX-3GP"
			(at -1.1811 -2.7051 0)
			(unlocked yes)
			(layer "B.Fab")
			(hide yes)
			(effects
				(font
					(size 1.016 1.016)
					(thickness 0.1524)
				)
				(justify mirror)
			)
		)
		(property "Device Type" "C402H22"
			(at -1.1811 -4.2291 0)
			(unlocked yes)
			(layer "B.Fab")
			(hide yes)
			(effects
				(font
					(size 1.016 1.016)
					(thickness 0.1524)
				)
				(justify mirror)
			)
		)
		(duplicate_pad_numbers_are_jumpers no)
		(fp_rect
			(start 0.4318 0.9525)
			(end -0.4318 -0.9525)
			(stroke
				(width 0)
				(type default)
			)
			(fill no)
			(layer "B.CrtYd")
		)
		(fp_rect
			(start 0.4318 0.9525)
			(end -0.4318 -0.9525)
			(stroke
				(width 0)
				(type default)
			)
			(fill no)
			(layer "B.Fab")
		)
		(pad "1" smd custom
			(at 0 -0.4445 180)
			(size 0.1524 0.1524)
			(layers "B.Cu" "B.Mask" "B.Paste")
			(net "P3V3_STBY")
			(options
				(clearance outline)
				(anchor circle)
			)
			(primitives
				(gr_poly
					(pts
						(arc
							(start 0.3048 0.2032)
							(mid 0.275042 0.275042)
							(end 0.2032 0.3048)
						)
						(arc
							(start -0.2032 0.3048)
							(mid -0.275042 0.275042)
							(end -0.3048 0.2032)
						)
						(arc
							(start -0.3048 -0.2032)
							(mid -0.275042 -0.275042)
							(end -0.2032 -0.3048)
						)
						(arc
							(start 0.2032 -0.3048)
							(mid 0.275042 -0.275042)
							(end 0.3048 -0.2032)
						)
					)
					(width 0)
					(fill yes)
				)
			)
		)
		(pad "2" smd custom
			(at 0 0.4445 180)
			(size 0.1524 0.1524)
			(layers "B.Cu" "B.Mask" "B.Paste")
			(net "GND")
			(options
				(clearance outline)
				(anchor circle)
			)
			(primitives
				(gr_poly
					(pts
						(arc
							(start 0.3048 0.2032)
							(mid 0.275042 0.275042)
							(end 0.2032 0.3048)
						)
						(arc
							(start -0.2032 0.3048)
							(mid -0.275042 0.275042)
							(end -0.3048 0.2032)
						)
						(arc
							(start -0.3048 -0.2032)
							(mid -0.275042 -0.275042)
							(end -0.2032 -0.3048)
						)
						(arc
							(start 0.2032 -0.3048)
							(mid 0.275042 -0.275042)
							(end 0.3048 -0.2032)
						)
					)
					(width 0)
					(fill yes)
				)
			)
		)
	)
	(footprint ""
		(layer "B.Cu")
		(at 219.964 -20.955 90)
		(property "Reference" "TP213"
			(at 0 0 90)
			(layer "B.SilkS")
			(hide yes)
			(effects
				(font
					(size 1.27 1.27)
				)
				(justify mirror)
			)
		)
		(property "Value" "TPAD28-2-GP"
			(at 0.0127 -1.6637 90)
			(unlocked yes)
			(layer "B.Fab")
			(hide yes)
			(effects
				(font
					(size 1.016 1.016)
					(thickness 0.1524)
				)
				(justify mirror)
			)
		)
		(property "Device Type" "TPAD28"
			(at 0.0127 -3.1877 90)
			(unlocked yes)
			(layer "B.Fab")
			(hide yes)
			(effects
				(font
					(size 1.016 1.016)
					(thickness 0.1524)
				)
				(justify mirror)
			)
		)
		(duplicate_pad_numbers_are_jumpers no)
		(fp_poly
			(pts
				(arc
					(start 0 0.3556)
					(mid 0 -0.3556)
					(end 0 0.3556)
				)
			)
			(stroke
				(width 0)
				(type default)
			)
			(fill no)
			(layer "B.CrtYd")
		)
		(fp_poly
			(pts
				(arc
					(start 0 0.6096)
					(mid 0 -0.6096)
					(end 0 0.6096)
				)
			)
			(stroke
				(width 0)
				(type default)
			)
			(fill no)
			(layer "B.Fab")
		)
		(pad "1" smd circle
			(at 0 0 270)
			(size 0.7112 0.7112)
			(layers "B.Cu" "B.Mask" "B.Paste")
			(net "MDIO")
		)
	)
)
